(kicad_pcb
	(version 20260206)
	(generator "pcbnew")
	(generator_version "10.0")
	(general
		(thickness 1.6)
		(legacy_teardrops no)
	)
	(paper "A4")
	(title_block
		(title "v1-chassis-manager — T6M_CM_d_v01_1031_1645.brd")
		(comment 1 "Open CloudServer (Microsoft) / footprint 1507 of 2512 (U2), pads 240-361 of 1283")
	)
	(layers
		(0 "F.Cu" signal "TOP")
		(4 "In1.Cu" signal "GND1")
		(6 "In2.Cu" signal "IN1")
		(8 "In3.Cu" signal "VCC1")
		(10 "In4.Cu" signal "VCC2")
		(12 "In5.Cu" signal "GND2")
		(14 "In6.Cu" signal "IN2")
		(16 "In7.Cu" signal "IN3")
		(18 "In8.Cu" signal "GND3")
		(2 "B.Cu" signal "BOTTOM")
		(9 "F.Adhes" user "F.Adhesive")
		(11 "B.Adhes" user "B.Adhesive")
		(13 "F.Paste" user "Package Geometry/Pastemask Top")
		(15 "B.Paste" user "Package Geometry/Pastemask Bottom")
		(5 "F.SilkS" user "Ref Des/Silkscreen Top")
		(7 "B.SilkS" user "Ref Des/Silkscreen Bottom")
		(1 "F.Mask" user "Board Geometry/Soldermask Top")
		(3 "B.Mask" user "Board Geometry/Soldermask Bottom")
		(17 "Dwgs.User" user "User.Drawings")
		(19 "Cmts.User" user "User.Comments")
		(21 "Eco1.User" user "User.Eco1")
		(23 "Eco2.User" user "User.Eco2")
		(25 "Edge.Cuts" user "Board Geometry/Outline")
		(27 "Margin" user)
		(31 "F.CrtYd" user "Package Geometry/Place Bound Top")
		(29 "B.CrtYd" user "Package Geometry/Place Bound Bottom")
		(35 "F.Fab" user "Ref Des/Assembly Top")
		(33 "B.Fab" user "Ref Des/Assembly Bottom")
	)
	(footprint ""
		(layer "F.Cu")
		(at 58.000646 -75.799442)
		(property "Reference" "U2"
			(at -20.2438 -18.364708 0)
			(unlocked yes)
			(layer "F.SilkS")
			(effects
				(font
					(size 1.6002 1.1938)
					(thickness 0.1524)
				)
				(justify left)
			)
		)
		(property "Value" ""
			(at 0 0 0)
			(layer "F.Fab")
			(effects
				(font
					(size 1.27 1.27)
				)
			)
		)
		(duplicate_pad_numbers_are_jumpers no)
		(pad "AJ65" smd circle
			(at 15.752318 0.617728)
			(size 0.3048 0.3048)
			(layers "F.Cu" "F.Mask" "F.Paste")
			(net "Net_438")
		)
		(pad "AK3" smd circle
			(at -15.247112 1.28651)
			(size 0.3048 0.3048)
			(layers "F.Cu" "F.Mask" "F.Paste")
			(net "GND")
		)
		(pad "AK5" smd circle
			(at -14.013688 1.316736)
			(size 0.3048 0.3048)
			(layers "F.Cu" "F.Mask" "F.Paste")
			(net "GND")
		)
		(pad "AK20" smd circle
			(at -6.841998 1.056132)
			(size 0.3048 0.3048)
			(layers "F.Cu" "F.Mask" "F.Paste")
			(net "GND")
		)
		(pad "AK62" smd circle
			(at 14.08049 1.114552)
			(size 0.3048 0.3048)
			(layers "F.Cu" "F.Mask" "F.Paste")
			(net "GND")
		)
		(pad "AK64" smd circle
			(at 15.242794 1.104646)
			(size 0.3048 0.3048)
			(layers "F.Cu" "F.Mask" "F.Paste")
			(net "GND")
		)
		(pad "AK66" smd oval
			(at 16.249396 1.335024 90)
			(size 0.254 0.3429)
			(layers "F.Cu" "F.Mask" "F.Paste")
			(net "GND")
		)
		(pad "AL1" smd oval
			(at -16.249396 1.542288 270)
			(size 0.254 0.3429)
			(layers "F.Cu" "F.Mask" "F.Paste")
			(net "GND")
		)
		(pad "AL2" smd circle
			(at -15.640812 1.891792)
			(size 0.3048 0.3048)
			(layers "F.Cu" "F.Mask" "F.Paste")
			(net "PD_CPU_NODE1_RP1_PERP")
		)
		(pad "AL4" smd circle
			(at -14.90091 1.897888)
			(size 0.3048 0.3048)
			(layers "F.Cu" "F.Mask" "F.Paste")
			(net "PD_CPU_NODE1_RP1_PERN")
		)
		(pad "AL5" smd circle
			(at -14.204442 1.994916)
			(size 0.3048 0.3048)
			(layers "F.Cu" "F.Mask" "F.Paste")
			(net "PD_CPU_NODE1_AL5")
		)
		(pad "AL8" smd circle
			(at -12.963398 1.756156)
			(size 0.3048 0.3048)
			(layers "F.Cu" "F.Mask" "F.Paste")
			(net "GND")
		)
		(pad "AL9" smd circle
			(at -12.201398 1.756156)
			(size 0.3048 0.3048)
			(layers "F.Cu" "F.Mask" "F.Paste")
			(net "Net_384")
		)
		(pad "AL11" smd circle
			(at -11.439398 1.756156)
			(size 0.3048 0.3048)
			(layers "F.Cu" "F.Mask" "F.Paste")
			(net "Net_376")
		)
		(pad "AL12" smd circle
			(at -10.677398 1.756156)
			(size 0.3048 0.3048)
			(layers "F.Cu" "F.Mask" "F.Paste")
			(net "GND")
		)
		(pad "AL14" smd circle
			(at -9.915398 1.756156)
			(size 0.3048 0.3048)
			(layers "F.Cu" "F.Mask" "F.Paste")
			(net "Net_389")
		)
		(pad "AL15" smd circle
			(at -9.153398 1.756156)
			(size 0.3048 0.3048)
			(layers "F.Cu" "F.Mask" "F.Paste")
			(net "Net_390")
		)
		(pad "AL17" smd circle
			(at -8.391398 1.756156)
			(size 0.3048 0.3048)
			(layers "F.Cu" "F.Mask" "F.Paste")
			(net "GND")
		)
		(pad "AL18" smd circle
			(at -7.629398 1.756156)
			(size 0.3048 0.3048)
			(layers "F.Cu" "F.Mask" "F.Paste")
			(net "P1V05_NODE1")
		)
		(pad "AL20" smd circle
			(at -6.929374 1.756156)
			(size 0.3048 0.3048)
			(layers "F.Cu" "F.Mask" "F.Paste")
			(net "P1V05_NODE1")
		)
		(pad "AL21" smd circle
			(at -6.00075 1.6002)
			(size 0.381 0.381)
			(layers "F.Cu" "F.Mask" "F.Paste")
			(net "P1V05_NODE1")
		)
		(pad "AL23" smd circle
			(at -5.20065 1.6002)
			(size 0.381 0.381)
			(layers "F.Cu" "F.Mask" "F.Paste")
			(net "P1V05_NODE1")
		)
		(pad "AL25" smd circle
			(at -4.40055 1.6002)
			(size 0.381 0.381)
			(layers "F.Cu" "F.Mask" "F.Paste")
			(net "P1V05_NODE1")
		)
		(pad "AL26" smd circle
			(at -3.60045 1.6002)
			(size 0.381 0.381)
			(layers "F.Cu" "F.Mask" "F.Paste")
			(net "P1V05_NODE1")
		)
		(pad "AL28" smd circle
			(at -2.80035 1.6002)
			(size 0.381 0.381)
			(layers "F.Cu" "F.Mask" "F.Paste")
			(net "P1V05_NODE1")
		)
		(pad "AL29" smd circle
			(at -2.00025 1.6002)
			(size 0.381 0.381)
			(layers "F.Cu" "F.Mask" "F.Paste")
			(net "P1V05_NODE1")
		)
		(pad "AL31" smd circle
			(at -1.20015 1.6002)
			(size 0.381 0.381)
			(layers "F.Cu" "F.Mask" "F.Paste")
			(net "GND")
		)
		(pad "AL32" smd circle
			(at -0.40005 1.6002)
			(size 0.381 0.381)
			(layers "F.Cu" "F.Mask" "F.Paste")
			(net "P1V05_NODE1")
		)
		(pad "AL34" smd circle
			(at 0.40005 1.6002)
			(size 0.381 0.381)
			(layers "F.Cu" "F.Mask" "F.Paste")
			(net "GND")
		)
		(pad "AL36" smd circle
			(at 1.20015 1.6002)
			(size 0.381 0.381)
			(layers "F.Cu" "F.Mask" "F.Paste")
			(net "P1V05_NODE1")
		)
		(pad "AL38" smd circle
			(at 2.00025 1.6002)
			(size 0.381 0.381)
			(layers "F.Cu" "F.Mask" "F.Paste")
			(net "GND")
		)
		(pad "AL39" smd circle
			(at 2.80035 1.6002)
			(size 0.381 0.381)
			(layers "F.Cu" "F.Mask" "F.Paste")
			(net "P1V05_NODE1")
		)
		(pad "AL41" smd circle
			(at 3.60045 1.6002)
			(size 0.381 0.381)
			(layers "F.Cu" "F.Mask" "F.Paste")
			(net "GND")
		)
		(pad "AL42" smd circle
			(at 4.40055 1.6002)
			(size 0.381 0.381)
			(layers "F.Cu" "F.Mask" "F.Paste")
			(net "P1V05_NODE1")
		)
		(pad "AL44" smd circle
			(at 5.20065 1.6002)
			(size 0.381 0.381)
			(layers "F.Cu" "F.Mask" "F.Paste")
			(net "GND")
		)
		(pad "AL46" smd circle
			(at 6.00075 1.6002)
			(size 0.381 0.381)
			(layers "F.Cu" "F.Mask" "F.Paste")
			(net "GND")
		)
		(pad "AL47" smd circle
			(at 6.929374 1.51638)
			(size 0.3048 0.3048)
			(layers "F.Cu" "F.Mask" "F.Paste")
			(net "P1V05_NODE1")
		)
		(pad "AL49" smd circle
			(at 7.629398 1.51638)
			(size 0.3048 0.3048)
			(layers "F.Cu" "F.Mask" "F.Paste")
			(net "P1V05_NODE1")
		)
		(pad "AL50" smd circle
			(at 8.391398 1.51638)
			(size 0.3048 0.3048)
			(layers "F.Cu" "F.Mask" "F.Paste")
			(net "GND")
		)
		(pad "AL52" smd circle
			(at 9.153398 1.51638)
			(size 0.3048 0.3048)
			(layers "F.Cu" "F.Mask" "F.Paste")
			(net "XDP_CPU_NODE1_VISA16")
		)
		(pad "AL53" smd circle
			(at 9.915398 1.51638)
			(size 0.3048 0.3048)
			(layers "F.Cu" "F.Mask" "F.Paste")
			(net "XDP_CPU_NODE1_VISA15")
		)
		(pad "AL55" smd circle
			(at 10.677398 1.51638)
			(size 0.3048 0.3048)
			(layers "F.Cu" "F.Mask" "F.Paste")
			(net "GND")
		)
		(pad "AL56" smd circle
			(at 11.439398 1.51638)
			(size 0.3048 0.3048)
			(layers "F.Cu" "F.Mask" "F.Paste")
			(net "Net_442")
		)
		(pad "AL58" smd circle
			(at 12.201398 1.51638)
			(size 0.3048 0.3048)
			(layers "F.Cu" "F.Mask" "F.Paste")
			(net "Net_437")
		)
		(pad "AL59" smd circle
			(at 12.963398 1.51638)
			(size 0.3048 0.3048)
			(layers "F.Cu" "F.Mask" "F.Paste")
			(net "GND")
		)
		(pad "AL62" smd circle
			(at 14.204442 1.807972)
			(size 0.3048 0.3048)
			(layers "F.Cu" "F.Mask" "F.Paste")
			(net "M1_DQ_NODE1_DQ62")
		)
		(pad "AL63" smd circle
			(at 14.90091 1.716024)
			(size 0.3048 0.3048)
			(layers "F.Cu" "F.Mask" "F.Paste")
			(net "M1_DQ_NODE1_DQ60")
		)
		(pad "AL65" smd circle
			(at 15.639034 1.684528)
			(size 0.3048 0.3048)
			(layers "F.Cu" "F.Mask" "F.Paste")
			(net "M1_DQ_NODE1_DQ63")
		)
		(pad "AM8" smd circle
			(at -12.963398 2.45618)
			(size 0.3048 0.3048)
			(layers "F.Cu" "F.Mask" "F.Paste")
			(net "GND")
		)
		(pad "AM9" smd circle
			(at -12.201398 2.45618)
			(size 0.3048 0.3048)
			(layers "F.Cu" "F.Mask" "F.Paste")
			(net "Net_382")
		)
		(pad "AM11" smd circle
			(at -11.439398 2.45618)
			(size 0.3048 0.3048)
			(layers "F.Cu" "F.Mask" "F.Paste")
			(net "Net_383")
		)
		(pad "AM12" smd circle
			(at -10.677398 2.45618)
			(size 0.3048 0.3048)
			(layers "F.Cu" "F.Mask" "F.Paste")
			(net "GND")
		)
		(pad "AM14" smd circle
			(at -9.915398 2.45618)
			(size 0.3048 0.3048)
			(layers "F.Cu" "F.Mask" "F.Paste")
			(net "Net_454")
		)
		(pad "AM15" smd circle
			(at -9.153398 2.45618)
			(size 0.3048 0.3048)
			(layers "F.Cu" "F.Mask" "F.Paste")
			(net "Net_391")
		)
		(pad "AM17" smd circle
			(at -8.391398 2.45618)
			(size 0.3048 0.3048)
			(layers "F.Cu" "F.Mask" "F.Paste")
			(net "GND")
		)
		(pad "AM18" smd circle
			(at -7.629398 2.45618)
			(size 0.3048 0.3048)
			(layers "F.Cu" "F.Mask" "F.Paste")
			(net "GND")
		)
		(pad "AM20" smd circle
			(at -6.929374 2.45618)
			(size 0.3048 0.3048)
			(layers "F.Cu" "F.Mask" "F.Paste")
			(net "GND")
		)
		(pad "AM21" smd circle
			(at -6.00075 2.4003)
			(size 0.381 0.381)
			(layers "F.Cu" "F.Mask" "F.Paste")
			(net "P1V5_NODE1_AM21")
		)
		(pad "AM23" smd circle
			(at -5.20065 2.4003)
			(size 0.381 0.381)
			(layers "F.Cu" "F.Mask" "F.Paste")
			(net "PD_CPU_NODE1_AM23")
		)
		(pad "AM25" smd circle
			(at -4.40055 2.4003)
			(size 0.381 0.381)
			(layers "F.Cu" "F.Mask" "F.Paste")
			(net "GND")
		)
		(pad "AM26" smd circle
			(at -3.60045 2.4003)
			(size 0.381 0.381)
			(layers "F.Cu" "F.Mask" "F.Paste")
			(net "GND")
		)
		(pad "AM28" smd circle
			(at -2.80035 2.4003)
			(size 0.381 0.381)
			(layers "F.Cu" "F.Mask" "F.Paste")
			(net "P1V5_NODE1")
		)
		(pad "AM29" smd circle
			(at -2.00025 2.4003)
			(size 0.381 0.381)
			(layers "F.Cu" "F.Mask" "F.Paste")
			(net "GND")
		)
		(pad "AM31" smd circle
			(at -1.20015 2.4003)
			(size 0.381 0.381)
			(layers "F.Cu" "F.Mask" "F.Paste")
			(net "P1V05_NODE1")
		)
		(pad "AM32" smd circle
			(at -0.40005 2.4003)
			(size 0.381 0.381)
			(layers "F.Cu" "F.Mask" "F.Paste")
			(net "GND")
		)
		(pad "AM34" smd circle
			(at 0.40005 2.4003)
			(size 0.381 0.381)
			(layers "F.Cu" "F.Mask" "F.Paste")
			(net "P1V05_NODE1")
		)
		(pad "AM36" smd circle
			(at 1.20015 2.4003)
			(size 0.381 0.381)
			(layers "F.Cu" "F.Mask" "F.Paste")
			(net "GND")
		)
		(pad "AM38" smd circle
			(at 2.00025 2.4003)
			(size 0.381 0.381)
			(layers "F.Cu" "F.Mask" "F.Paste")
			(net "P1V05_NODE1")
		)
		(pad "AM39" smd circle
			(at 2.80035 2.4003)
			(size 0.381 0.381)
			(layers "F.Cu" "F.Mask" "F.Paste")
			(net "GND")
		)
		(pad "AM41" smd circle
			(at 3.60045 2.4003)
			(size 0.381 0.381)
			(layers "F.Cu" "F.Mask" "F.Paste")
			(net "P1V05_NODE1")
		)
		(pad "AM42" smd circle
			(at 4.40055 2.4003)
			(size 0.381 0.381)
			(layers "F.Cu" "F.Mask" "F.Paste")
			(net "GND")
		)
		(pad "AM44" smd circle
			(at 5.20065 2.4003)
			(size 0.381 0.381)
			(layers "F.Cu" "F.Mask" "F.Paste")
			(net "GND")
		)
		(pad "AM46" smd circle
			(at 6.00075 2.4003)
			(size 0.381 0.381)
			(layers "F.Cu" "F.Mask" "F.Paste")
			(net "GND")
		)
		(pad "AM47" smd circle
			(at 6.929374 2.216404)
			(size 0.3048 0.3048)
			(layers "F.Cu" "F.Mask" "F.Paste")
			(net "GND")
		)
		(pad "AM49" smd circle
			(at 7.629398 2.216404)
			(size 0.3048 0.3048)
			(layers "F.Cu" "F.Mask" "F.Paste")
			(net "GND")
		)
		(pad "AM50" smd circle
			(at 8.391398 2.216404)
			(size 0.3048 0.3048)
			(layers "F.Cu" "F.Mask" "F.Paste")
			(net "GND")
		)
		(pad "AM52" smd circle
			(at 9.153398 2.216404)
			(size 0.3048 0.3048)
			(layers "F.Cu" "F.Mask" "F.Paste")
			(net "XDP_CPU_NODE1_VISA10")
		)
		(pad "AM53" smd circle
			(at 9.915398 2.216404)
			(size 0.3048 0.3048)
			(layers "F.Cu" "F.Mask" "F.Paste")
			(net "XDP_CPU_NODE1_VISA9")
		)
		(pad "AM55" smd circle
			(at 10.677398 2.216404)
			(size 0.3048 0.3048)
			(layers "F.Cu" "F.Mask" "F.Paste")
			(net "GND")
		)
		(pad "AM56" smd circle
			(at 11.439398 2.216404)
			(size 0.3048 0.3048)
			(layers "F.Cu" "F.Mask" "F.Paste")
			(net "XDP_CPU_NODE1_VISA13")
		)
		(pad "AM58" smd circle
			(at 12.201398 2.216404)
			(size 0.3048 0.3048)
			(layers "F.Cu" "F.Mask" "F.Paste")
			(net "XDP_CPU_NODE1_VISA12")
		)
		(pad "AM59" smd circle
			(at 12.963398 2.216404)
			(size 0.3048 0.3048)
			(layers "F.Cu" "F.Mask" "F.Paste")
			(net "GND")
		)
		(pad "AN2" smd circle
			(at -15.639034 2.818384)
			(size 0.3048 0.3048)
			(layers "F.Cu" "F.Mask" "F.Paste")
			(net "PD_CPU_NODE1_RP1_PERN")
		)
		(pad "AN4" smd circle
			(at -14.90091 2.786888)
			(size 0.3048 0.3048)
			(layers "F.Cu" "F.Mask" "F.Paste")
			(net "PD_CPU_NODE1_RP1_PERP")
		)
		(pad "AN5" smd circle
			(at -14.204442 2.69494)
			(size 0.3048 0.3048)
			(layers "F.Cu" "F.Mask" "F.Paste")
			(net "PD_CPU_NODE1_AN5")
		)
		(pad "AN47" smd circle
			(at 6.841998 2.916428)
			(size 0.3048 0.3048)
			(layers "F.Cu" "F.Mask" "F.Paste")
			(net "GND")
		)
		(pad "AN62" smd circle
			(at 14.204442 2.507996)
			(size 0.3048 0.3048)
			(layers "F.Cu" "F.Mask" "F.Paste")
			(net "GND")
		)
		(pad "AN63" smd circle
			(at 14.90091 2.605024)
			(size 0.3048 0.3048)
			(layers "F.Cu" "F.Mask" "F.Paste")
			(net "M_DDR3_NODE1_DQS7P")
		)
		(pad "AN65" smd circle
			(at 15.640812 2.61112)
			(size 0.3048 0.3048)
			(layers "F.Cu" "F.Mask" "F.Paste")
			(net "M1_DQ_NODE1_DQ59")
		)
		(pad "AN66" smd oval
			(at 16.249396 2.960624 90)
			(size 0.254 0.3429)
			(layers "F.Cu" "F.Mask" "F.Paste")
			(net "GND")
		)
		(pad "AP1" smd oval
			(at -16.249396 3.167888 270)
			(size 0.254 0.3429)
			(layers "F.Cu" "F.Mask" "F.Paste")
			(net "GND")
		)
		(pad "AP3" smd circle
			(at -15.242794 3.398266)
			(size 0.3048 0.3048)
			(layers "F.Cu" "F.Mask" "F.Paste")
			(net "GND")
		)
		(pad "AP5" smd circle
			(at -14.08049 3.38836)
			(size 0.3048 0.3048)
			(layers "F.Cu" "F.Mask" "F.Paste")
			(net "GND")
		)
		(pad "AP20" smd circle
			(at -6.841998 3.156204)
			(size 0.3048 0.3048)
			(layers "F.Cu" "F.Mask" "F.Paste")
			(net "P1V05_NODE1")
		)
		(pad "AP21" smd circle
			(at -6.00075 3.2004)
			(size 0.381 0.381)
			(layers "F.Cu" "F.Mask" "F.Paste")
			(net "P1V05_NODE1")
		)
		(pad "AP23" smd circle
			(at -5.20065 3.2004)
			(size 0.381 0.381)
			(layers "F.Cu" "F.Mask" "F.Paste")
			(net "P1V05_NODE1")
		)
		(pad "AP25" smd circle
			(at -4.40055 3.2004)
			(size 0.381 0.381)
			(layers "F.Cu" "F.Mask" "F.Paste")
			(net "P1V05_NODE1")
		)
		(pad "AP26" smd circle
			(at -3.60045 3.2004)
			(size 0.381 0.381)
			(layers "F.Cu" "F.Mask" "F.Paste")
			(net "P1V05_NODE1")
		)
		(pad "AP28" smd circle
			(at -2.80035 3.2004)
			(size 0.381 0.381)
			(layers "F.Cu" "F.Mask" "F.Paste")
			(net "P1V05_NODE1")
		)
		(pad "AP29" smd circle
			(at -2.00025 3.2004)
			(size 0.381 0.381)
			(layers "F.Cu" "F.Mask" "F.Paste")
			(net "P1V05_NODE1")
		)
		(pad "AP31" smd circle
			(at -1.20015 3.2004)
			(size 0.381 0.381)
			(layers "F.Cu" "F.Mask" "F.Paste")
			(net "GND")
		)
		(pad "AP32" smd circle
			(at -0.40005 3.2004)
			(size 0.381 0.381)
			(layers "F.Cu" "F.Mask" "F.Paste")
			(net "P1V05_NODE1")
		)
		(pad "AP34" smd circle
			(at 0.40005 3.2004)
			(size 0.381 0.381)
			(layers "F.Cu" "F.Mask" "F.Paste")
			(net "GND")
		)
		(pad "AP36" smd circle
			(at 1.20015 3.2004)
			(size 0.381 0.381)
			(layers "F.Cu" "F.Mask" "F.Paste")
			(net "P1V05_NODE1")
		)
		(pad "AP38" smd circle
			(at 2.00025 3.2004)
			(size 0.381 0.381)
			(layers "F.Cu" "F.Mask" "F.Paste")
			(net "P1V05_NODE1")
		)
		(pad "AP39" smd circle
			(at 2.80035 3.2004)
			(size 0.381 0.381)
			(layers "F.Cu" "F.Mask" "F.Paste")
			(net "P1V05_NODE1")
		)
		(pad "AP41" smd circle
			(at 3.60045 3.2004)
			(size 0.381 0.381)
			(layers "F.Cu" "F.Mask" "F.Paste")
			(net "P1V05_NODE1")
		)
		(pad "AP42" smd circle
			(at 4.40055 3.2004)
			(size 0.381 0.381)
			(layers "F.Cu" "F.Mask" "F.Paste")
			(net "P1V05_NODE1")
		)
		(pad "AP44" smd circle
			(at 5.20065 3.2004)
			(size 0.381 0.381)
			(layers "F.Cu" "F.Mask" "F.Paste")
			(net "P1V05_NODE1")
		)
		(pad "AP46" smd circle
			(at 6.00075 3.2004)
			(size 0.381 0.381)
			(layers "F.Cu" "F.Mask" "F.Paste")
			(net "P1V05_NODE1")
		)
		(pad "AP62" smd circle
			(at 14.013688 3.186176)
			(size 0.3048 0.3048)
			(layers "F.Cu" "F.Mask" "F.Paste")
			(net "GND")
		)
		(pad "AP64" smd circle
			(at 15.247112 3.216402)
			(size 0.3048 0.3048)
			(layers "F.Cu" "F.Mask" "F.Paste")
			(net "M_DDR3_NODE1_DQS7N")
		)
		(pad "AR2" smd circle
			(at -15.752318 3.885184)
			(size 0.3048 0.3048)
			(layers "F.Cu" "F.Mask" "F.Paste")
			(net "PD_CPU_NODE1_RP1_PERN")
		)
		(pad "AR4" smd circle
			(at -14.794738 3.938016)
			(size 0.3048 0.3048)
			(layers "F.Cu" "F.Mask" "F.Paste")
			(net "PD_CPU_NODE1_RP1_PERP")
		)
		(pad "AR7" smd circle
			(at -13.344398 3.742436)
			(size 0.3048 0.3048)
			(layers "F.Cu" "F.Mask" "F.Paste")
			(net "GND")
		)
		(pad "AR8" smd circle
			(at -12.582398 3.742436)
			(size 0.3048 0.3048)
			(layers "F.Cu" "F.Mask" "F.Paste")
			(net "Net_385")
		)
		(pad "AR10" smd circle
			(at -11.820398 3.742436)
			(size 0.3048 0.3048)
			(layers "F.Cu" "F.Mask" "F.Paste")
			(net "Net_453")
		)
		(pad "AR11" smd circle
			(at -11.058398 3.742436)
			(size 0.3048 0.3048)
			(layers "F.Cu" "F.Mask" "F.Paste")
			(net "GND")
		)
		(pad "AR13" smd circle
			(at -10.296398 3.742436)
			(size 0.3048 0.3048)
			(layers "F.Cu" "F.Mask" "F.Paste")
			(net "GND")
		)
		(pad "AR14" smd circle
			(at -9.534398 3.742436)
			(size 0.3048 0.3048)
			(layers "F.Cu" "F.Mask" "F.Paste")
			(net "Net_378")
		)
		(pad "AR16" smd circle
			(at -8.772398 3.742436)
			(size 0.3048 0.3048)
			(layers "F.Cu" "F.Mask" "F.Paste")
			(net "Net_381")
		)
		(pad "AR17" smd circle
			(at -8.010398 3.742436)
			(size 0.3048 0.3048)
			(layers "F.Cu" "F.Mask" "F.Paste")
			(net "GND")
		)
	)
)
